# BASEBOARD_FAB2 (Tioga Pass) — schematic netlist excerpt (pin names and nets, part order shuffled) for the footprints in the layout excerpt that follows; sources: Cadence DE-HDL packaged netlist, KiCad conversion of Wiwynn_Tioga_Pass_MB.brd

R8C7  RES  4.75K 1% CHIP  pkg 0402  page 133 : A = P3V3_STBY ; B = FM_SLT_CFG0
C4W2  CAP  220PF 50V 10% X7R  pkg 0402LF  page 213 : A = A_TSENSE_PVCCIO_CPU1 ; B = GND
C4G23  CAP  1000PF 50V 10% EMPTY  pkg 0402LF  page 221 : A = FM_PVTT_ABC_EN_R ; B = GND

(kicad_pcb
	(version 20260206)
	(generator "pcbnew")
	(generator_version "10.0")
	(general
		(thickness 1.6)
		(legacy_teardrops no)
	)
	(paper "A4")
	(title_block
		(title "Wiwynn_Tioga_Pass_MB.brd")
		(comment 1 "Tioga Pass / footprints 1223-1225 of 4770")
	)
	(layers
		(0 "F.Cu" signal "TOP")
		(4 "In1.Cu" signal "L2GND")
		(6 "In2.Cu" signal "L3")
		(8 "In3.Cu" signal "L4GND")
		(10 "In4.Cu" signal "L5")
		(12 "In5.Cu" signal "L6GND")
		(14 "In6.Cu" signal "L7VCC")
		(16 "In7.Cu" signal "L8VCC")
		(18 "In8.Cu" signal "L9GND")
		(20 "In9.Cu" signal "L10")
		(22 "In10.Cu" signal "L11GND")
		(24 "In11.Cu" signal "L12")
		(26 "In12.Cu" signal "L13GND")
		(2 "B.Cu" signal "BOTTOM")
		(9 "F.Adhes" user "F.Adhesive")
		(11 "B.Adhes" user "B.Adhesive")
		(13 "F.Paste" user "Package Geometry/Pastemask Top")
		(15 "B.Paste" user "Package Geometry/Pastemask Bottom")
		(5 "F.SilkS" user "Ref Des/Silkscreen Top")
		(7 "B.SilkS" user "Ref Des/Silkscreen Bottom")
		(1 "F.Mask" user "Board Geometry/Soldermask Top")
		(3 "B.Mask" user "Board Geometry/Soldermask Bottom")
		(17 "Dwgs.User" user "User.Drawings")
		(19 "Cmts.User" user "User.Comments")
		(21 "Eco1.User" user "User.Eco1")
		(23 "Eco2.User" user "User.Eco2")
		(25 "Edge.Cuts" user "Board Geometry/Outline")
		(27 "Margin" user)
		(31 "F.CrtYd" user "Package Geometry/Place Bound Top")
		(29 "B.CrtYd" user "Package Geometry/Place Bound Bottom")
		(35 "F.Fab" user "Ref Des/Assembly Top")
		(33 "B.Fab" user "Ref Des/Assembly Bottom")
	)
	(footprint ""
		(layer "F.Cu")
		(at 181.339998 1.536192)
		(property "Reference" "C4G23"
			(at 0 0 0)
			(layer "F.SilkS")
			(hide yes)
			(effects
				(font
					(size 1.27 1.27)
				)
			)
		)
		(property "Value" ""
			(at 0 0 0)
			(layer "F.Fab")
			(effects
				(font
					(size 1.27 1.27)
				)
			)
		)
		(duplicate_pad_numbers_are_jumpers no)
		(fp_rect
			(start -0.3048 0.9906)
			(end 0.3048 -0.1016)
			(stroke
				(width 0)
				(type default)
			)
			(fill no)
			(layer "F.CrtYd")
		)
		(fp_line
			(start -0.3048 -0.1016)
			(end -0.3048 0.9906)
			(stroke
				(width 0.1)
				(type default)
			)
			(layer "F.Fab")
		)
		(fp_line
			(start -0.3048 0.9906)
			(end 0.3048 0.9906)
			(stroke
				(width 0.1)
				(type default)
			)
			(layer "F.Fab")
		)
		(fp_line
			(start 0.3048 -0.1016)
			(end -0.3048 -0.1016)
			(stroke
				(width 0.1)
				(type default)
			)
			(layer "F.Fab")
		)
		(fp_line
			(start 0.3048 0.9906)
			(end 0.3048 -0.1016)
			(stroke
				(width 0.1)
				(type default)
			)
			(layer "F.Fab")
		)
		(pad "1" smd rect
			(at 0 0)
			(size 0.508 0.508)
			(layers "F.Cu" "F.Mask" "F.Paste")
			(net "FM_PVTT_ABC_EN_R")
		)
		(pad "2" smd rect
			(at 0 0.889)
			(size 0.508 0.508)
			(layers "F.Cu" "F.Mask" "F.Paste")
			(net "GND")
		)
		(zone
			(layer "F.Cu")
			(hatch none 0.5)
			(connect_pads
				(clearance 0)
			)
			(min_thickness 0.25)
			(keepout
				(tracks allowed)
				(vias not_allowed)
				(pads allowed)
				(copperpour not_allowed)
				(footprints allowed)
			)
			(placement
				(enabled no)
				(sheetname "")
			)
			(fill
				(thermal_gap 0.5)
				(thermal_bridge_width 0.5)
				(island_removal_mode 0)
			)
			(polygon
				(pts
					(xy 181.085998 2.171192) (xy 181.593998 2.171192) (xy 181.593998 1.790192) (xy 181.085998 1.790192)
				)
			)
		)
		(zone
			(layer "F.Cu")
			(hatch none 0.5)
			(connect_pads
				(clearance 0)
			)
			(min_thickness 0.25)
			(keepout
				(tracks not_allowed)
				(vias allowed)
				(pads allowed)
				(copperpour not_allowed)
				(footprints allowed)
			)
			(placement
				(enabled no)
				(sheetname "")
			)
			(fill
				(thermal_gap 0.5)
				(thermal_bridge_width 0.5)
				(island_removal_mode 0)
			)
			(polygon
				(pts
					(xy 181.085998 2.171192) (xy 181.593998 2.171192) (xy 181.593998 1.790192) (xy 181.085998 1.790192)
				)
			)
		)
	)
	(footprint ""
		(layer "F.Cu")
		(at 411.0355 -109.855 -90)
		(property "Reference" "R8C7"
			(at 0 0 270)
			(layer "F.SilkS")
			(hide yes)
			(effects
				(font
					(size 1.27 1.27)
				)
			)
		)
		(property "Value" ""
			(at 0 0 270)
			(layer "F.Fab")
			(effects
				(font
					(size 1.27 1.27)
				)
			)
		)
		(duplicate_pad_numbers_are_jumpers no)
		(fp_poly
			(pts
				(xy -0.2794 -0.1016) (xy 0.2794 -0.1016) (xy 0.2794 0.9906) (xy -0.2794 0.9906)
			)
			(stroke
				(width 0)
				(type default)
			)
			(fill no)
			(layer "F.CrtYd")
		)
		(fp_line
			(start -0.2794 0.9906)
			(end 0.2794 0.9906)
			(stroke
				(width 0.1)
				(type default)
			)
			(layer "F.Fab")
		)
		(fp_line
			(start 0.2794 0.9906)
			(end 0.2794 -0.1016)
			(stroke
				(width 0.1)
				(type default)
			)
			(layer "F.Fab")
		)
		(fp_line
			(start -0.2794 -0.1016)
			(end -0.2794 0.9906)
			(stroke
				(width 0.1)
				(type default)
			)
			(layer "F.Fab")
		)
		(fp_line
			(start 0.2794 -0.1016)
			(end -0.2794 -0.1016)
			(stroke
				(width 0.1)
				(type default)
			)
			(layer "F.Fab")
		)
		(pad "1" smd rect
			(at 0 0 270)
			(size 0.508 0.508)
			(layers "F.Cu" "F.Mask" "F.Paste")
			(net "P3V3_STBY")
		)
		(pad "2" smd rect
			(at 0 0.889 270)
			(size 0.508 0.508)
			(layers "F.Cu" "F.Mask" "F.Paste")
			(net "FM_SLT_CFG0")
		)
		(zone
			(layer "F.Cu")
			(hatch none 0.5)
			(connect_pads
				(clearance 0)
			)
			(min_thickness 0.25)
			(keepout
				(tracks not_allowed)
				(vias allowed)
				(pads allowed)
				(copperpour not_allowed)
				(footprints allowed)
			)
			(placement
				(enabled no)
				(sheetname "")
			)
			(fill
				(thermal_gap 0.5)
				(thermal_bridge_width 0.5)
				(island_removal_mode 0)
			)
			(polygon
				(pts
					(xy 410.4005 -110.109) (xy 410.4005 -109.601) (xy 410.7815 -109.601) (xy 410.7815 -110.109)
				)
			)
		)
		(zone
			(layer "F.Cu")
			(hatch none 0.5)
			(connect_pads
				(clearance 0)
			)
			(min_thickness 0.25)
			(keepout
				(tracks allowed)
				(vias not_allowed)
				(pads allowed)
				(copperpour not_allowed)
				(footprints allowed)
			)
			(placement
				(enabled no)
				(sheetname "")
			)
			(fill
				(thermal_gap 0.5)
				(thermal_bridge_width 0.5)
				(island_removal_mode 0)
			)
			(polygon
				(pts
					(xy 410.7815 -110.109) (xy 410.7815 -109.601) (xy 410.4005 -109.601) (xy 410.4005 -110.109)
				)
			)
		)
	)
	(footprint ""
		(layer "F.Cu")
		(at 173.736 -64.63538 90)
		(property "Reference" "C4W2"
			(at -0.8382 -0.67818 90)
			(unlocked yes)
			(layer "F.SilkS")
			(effects
				(font
					(size 0.4064 0.254)
					(thickness 0.1524)
				)
				(justify left)
			)
		)
		(property "Value" ""
			(at 0 0 90)
			(layer "F.Fab")
			(effects
				(font
					(size 1.27 1.27)
				)
			)
		)
		(duplicate_pad_numbers_are_jumpers no)
		(fp_poly
			(pts
				(xy 0.3048 -0.1016) (xy 0.3048 0.9906) (xy -0.3048 0.9906) (xy -0.3048 -0.1016)
			)
			(stroke
				(width 0)
				(type default)
			)
			(fill no)
			(layer "F.CrtYd")
		)
		(fp_line
			(start 0.3048 -0.1016)
			(end -0.3048 -0.1016)
			(stroke
				(width 0.1)
				(type default)
			)
			(layer "F.Fab")
		)
		(fp_line
			(start -0.3048 -0.1016)
			(end -0.3048 0.9906)
			(stroke
				(width 0.1)
				(type default)
			)
			(layer "F.Fab")
		)
		(fp_line
			(start 0.3048 0.9906)
			(end 0.3048 -0.1016)
			(stroke
				(width 0.1)
				(type default)
			)
			(layer "F.Fab")
		)
		(fp_line
			(start -0.3048 0.9906)
			(end 0.3048 0.9906)
			(stroke
				(width 0.1)
				(type default)
			)
			(layer "F.Fab")
		)
		(pad "1" smd rect
			(at 0 0 90)
			(size 0.508 0.508)
			(layers "F.Cu" "F.Mask" "F.Paste")
			(net "A_TSENSE_PVCCIO_CPU1")
		)
		(pad "2" smd rect
			(at 0 0.889 90)
			(size 0.508 0.508)
			(layers "F.Cu" "F.Mask" "F.Paste")
			(net "GND")
		)
		(zone
			(layer "F.Cu")
			(hatch none 0.5)
			(connect_pads
				(clearance 0)
			)
			(min_thickness 0.25)
			(keepout
				(tracks allowed)
				(vias not_allowed)
				(pads allowed)
				(copperpour not_allowed)
				(footprints allowed)
			)
			(placement
				(enabled no)
				(sheetname "")
			)
			(fill
				(thermal_gap 0.5)
				(thermal_bridge_width 0.5)
				(island_removal_mode 0)
			)
			(polygon
				(pts
					(xy 173.99 -64.38138) (xy 173.99 -64.88938) (xy 174.371 -64.88938) (xy 174.371 -64.38138)
				)
			)
		)
		(zone
			(layer "F.Cu")
			(hatch none 0.5)
			(connect_pads
				(clearance 0)
			)
			(min_thickness 0.25)
			(keepout
				(tracks not_allowed)
				(vias allowed)
				(pads allowed)
				(copperpour not_allowed)
				(footprints allowed)
			)
			(placement
				(enabled no)
				(sheetname "")
			)
			(fill
				(thermal_gap 0.5)
				(thermal_bridge_width 0.5)
				(island_removal_mode 0)
			)
			(polygon
				(pts
					(xy 174.371 -64.38138) (xy 174.371 -64.88938) (xy 173.99 -64.88938) (xy 173.99 -64.38138)
				)
			)
		)
	)
)
